(kicad_pcb
	(version 20241229)
	(generator "pcbnew")
	(generator_version "9.0")
	(general
		(thickness 1.63)
		(legacy_teardrops no)
	)
	(paper "A4")
	(title_block
		(title "CM4 Baseboard")
		(date "2026-01-05")
		(rev "1.1.1")
		(company "Antmicro Ltd")
		(comment 1 "www.antmicro.com")
		(comment 9 "footprints 85-89 of 506")
	)
	(layers
		(0 "F.Cu" signal)
		(4 "In1.Cu" power)
		(6 "In2.Cu" power)
		(8 "In3.Cu" signal)
		(10 "In4.Cu" signal)
		(2 "B.Cu" signal)
		(9 "F.Adhes" user "F.Adhesive")
		(11 "B.Adhes" user "B.Adhesive")
		(13 "F.Paste" user)
		(15 "B.Paste" user)
		(5 "F.SilkS" user "F.Silkscreen")
		(7 "B.SilkS" user "B.Silkscreen")
		(1 "F.Mask" user)
		(3 "B.Mask" user)
		(17 "Dwgs.User" user "User.Drawings")
		(19 "Cmts.User" user "User.Comments")
		(21 "Eco1.User" user "User.Eco1")
		(23 "Eco2.User" user "User.Eco2")
		(25 "Edge.Cuts" user)
		(27 "Margin" user)
		(31 "F.CrtYd" user "F.Courtyard")
		(29 "B.CrtYd" user "B.Courtyard")
		(35 "F.Fab" user)
		(33 "B.Fab" user)
	)
	(footprint "antmicro-footprints:R_0402_1005Metric"
		(layer "F.Cu")
		(at 137.142962 161.5415 90)
		(descr "Resistor SMD 0402")
		(tags "resistor SMD 0402")
		(property "Reference" "R604"
			(at -1.7335 1.232038 90)
			(layer "F.SilkS")
			(effects
				(font
					(size 0.7 0.7)
					(thickness 0.15)
				)
				(justify left bottom)
			)
		)
		(property "Value" "R_4k7_0402"
			(at -1.011843 1.772047 90)
			(layer "F.Fab")
			(effects
				(font
					(size 0.7 0.7)
					(thickness 0.15)
				)
				(justify left bottom)
			)
		)
		(property "Datasheet" "https://www.bourns.com/docs/product-datasheets/cr.pdf"
			(at 0 0 90)
			(layer "F.Fab")
			(hide yes)
			(effects
				(font
					(size 1.27 1.27)
					(thickness 0.15)
				)
			)
		)
		(property "Manufacturer" "Bourns"
			(at 0 0 90)
			(unlocked yes)
			(layer "F.Fab")
			(hide yes)
			(effects
				(font
					(size 1 1)
					(thickness 0.15)
				)
			)
		)
		(property "MPN" "CR0402-FX-4701GLF"
			(at 0 0 90)
			(unlocked yes)
			(layer "F.Fab")
			(hide yes)
			(effects
				(font
					(size 1 1)
					(thickness 0.15)
				)
			)
		)
		(property "Val" "4k7"
			(at 0 0 90)
			(unlocked yes)
			(layer "F.Fab")
			(hide yes)
			(effects
				(font
					(size 1 1)
					(thickness 0.15)
				)
			)
		)
		(property "License" "Apache-2.0"
			(at 0 0 90)
			(unlocked yes)
			(layer "F.Fab")
			(hide yes)
			(effects
				(font
					(size 1 1)
					(thickness 0.15)
				)
			)
		)
		(property "Author" "Antmicro"
			(at 0 0 90)
			(unlocked yes)
			(layer "F.Fab")
			(hide yes)
			(effects
				(font
					(size 1 1)
					(thickness 0.15)
				)
			)
		)
		(property "Tolerance" "1%"
			(at 0 0 90)
			(unlocked yes)
			(layer "F.Fab")
			(hide yes)
			(effects
				(font
					(size 1 1)
					(thickness 0.15)
				)
			)
		)
		(sheetname "/CSI/")
		(sheetfile "csi.kicad_sch")
		(attr smd)
		(fp_rect
			(start -0.925 -0.47)
			(end 0.925 0.47)
			(stroke
				(width 0.05)
				(type default)
			)
			(fill no)
			(layer "F.CrtYd")
		)
		(fp_rect
			(start -0.5 -0.25)
			(end 0.5 0.25)
			(stroke
				(width 0.15)
				(type solid)
			)
			(fill no)
			(layer "F.Fab")
		)
		(fp_text user "Author: Antmicro"
			(at -0.95 4.169 90)
			(layer "F.Fab")
			(effects
				(font
					(size 0.7 0.7)
					(thickness 0.15)
				)
				(justify left bottom)
			)
		)
		(fp_text user "License: Apache-2.0"
			(at -0.95 5.169 90)
			(layer "F.Fab")
			(effects
				(font
					(size 0.7 0.7)
					(thickness 0.15)
				)
				(justify left bottom)
			)
		)
		(fp_text user "${REFERENCE}"
			(at -0.95 3.168 90)
			(layer "F.Fab")
			(effects
				(font
					(size 0.7 0.7)
					(thickness 0.15)
				)
				(justify left bottom)
			)
		)
		(pad "1" smd roundrect
			(at -0.48 0 90)
			(size 0.59 0.64)
			(layers "F.Cu" "F.Mask" "F.Paste")
			(roundrect_rratio 0.25)
			(net 3 "GND")
			(pintype "passive")
		)
		(pad "2" smd roundrect
			(at 0.48 0 90)
			(size 0.59 0.64)
			(layers "F.Cu" "F.Mask" "F.Paste")
			(roundrect_rratio 0.25)
			(net 372 "Net-(U601-ISET)")
			(pintype "passive")
		)
	)
	(footprint "antmicro-footprints:LED_0603_1608Metric_G"
		(layer "F.Cu")
		(at 136.537962 156.0165 180)
		(descr "LED SMD 0603 Green")
		(tags "LED SMD 0603 Green")
		(property "Reference" "D601"
			(at -3.98 -0.4 0)
			(layer "F.SilkS")
			(effects
				(font
					(size 0.7 0.7)
					(thickness 0.15)
				)
				(justify right bottom)
			)
		)
		(property "Value" "LED_G_0603_KP-1608CGCK"
			(at -0.001 1.599 0)
			(layer "F.Fab")
			(effects
				(font
					(size 0.7 0.7)
					(thickness 0.15)
				)
				(justify right bottom)
			)
		)
		(property "Datasheet" "http://www.kingbright.com/attachments/file/psearch//000/00/00/KP-1608CGCK(Ver.23B).pdf"
			(at 0 0 180)
			(layer "F.Fab")
			(hide yes)
			(effects
				(font
					(size 1.27 1.27)
					(thickness 0.15)
				)
			)
		)
		(property "MPN" "KP-1608CGCK"
			(at 0 0 180)
			(unlocked yes)
			(layer "F.Fab")
			(hide yes)
			(effects
				(font
					(size 1 1)
					(thickness 0.15)
				)
			)
		)
		(property "Manufacturer" "Kingbright"
			(at 0 0 180)
			(unlocked yes)
			(layer "F.Fab")
			(hide yes)
			(effects
				(font
					(size 1 1)
					(thickness 0.15)
				)
			)
		)
		(property "Color" "Green"
			(at 0 0 180)
			(unlocked yes)
			(layer "F.Fab")
			(hide yes)
			(effects
				(font
					(size 1 1)
					(thickness 0.15)
				)
			)
		)
		(property "Author" "Antmicro"
			(at 0 0 180)
			(unlocked yes)
			(layer "F.Fab")
			(hide yes)
			(effects
				(font
					(size 1 1)
					(thickness 0.15)
				)
			)
		)
		(property "License" "Apache-2.0"
			(at 0 0 180)
			(unlocked yes)
			(layer "F.Fab")
			(hide yes)
			(effects
				(font
					(size 1 1)
					(thickness 0.15)
				)
			)
		)
		(sheetname "/CSI/")
		(sheetfile "csi.kicad_sch")
		(attr smd)
		(fp_line
			(start 0.22 0.35)
			(end -0.22 0.35)
			(stroke
				(width 0.15)
				(type solid)
			)
			(layer "F.SilkS")
		)
		(fp_line
			(start 0.22 -0.35)
			(end -0.22 -0.35)
			(stroke
				(width 0.15)
				(type solid)
			)
			(layer "F.SilkS")
		)
		(fp_line
			(start 0.105328 0.201008)
			(end 0.105328 -0.198992)
			(stroke
				(width 0.1)
				(type solid)
			)
			(layer "F.SilkS")
		)
		(fp_line
			(start 0.105328 0.201008)
			(end -0.094672 0.001008)
			(stroke
				(width 0.1)
				(type solid)
			)
			(layer "F.SilkS")
		)
		(fp_line
			(start 0.105328 0.001008)
			(end 0.24 0.001)
			(stroke
				(width 0.1)
				(type solid)
			)
			(layer "F.SilkS")
		)
		(fp_line
			(start -0.094672 0.201008)
			(end -0.094672 -0.198992)
			(stroke
				(width 0.1)
				(type solid)
			)
			(layer "F.SilkS")
		)
		(fp_line
			(start -0.094672 0.001008)
			(end 0.105328 -0.198992)
			(stroke
				(width 0.1)
				(type solid)
			)
			(layer "F.SilkS")
		)
		(fp_line
			(start -0.094672 0.001008)
			(end -0.24 0.001008)
			(stroke
				(width 0.1)
				(type solid)
			)
			(layer "F.SilkS")
		)
		(fp_line
			(start -1.18 -0.319)
			(end -1.18 0.321)
			(stroke
				(width 0.15)
				(type solid)
			)
			(layer "F.SilkS")
		)
		(fp_rect
			(start 1.25 0.65)
			(end -1.25 -0.65)
			(stroke
				(width 0.05)
				(type solid)
			)
			(fill no)
			(layer "F.CrtYd")
		)
		(fp_line
			(start 0.599 0)
			(end 0.201 0)
			(stroke
				(width 0.15)
				(type solid)
			)
			(layer "F.Fab")
		)
		(fp_line
			(start 0.201 0.2)
			(end 0.201 0)
			(stroke
				(width 0.15)
				(type solid)
			)
			(layer "F.Fab")
		)
		(fp_line
			(start 0.201 0)
			(end 0.201 -0.202)
			(stroke
				(width 0.15)
				(type solid)
			)
			(layer "F.Fab")
		)
		(fp_line
			(start 0.201 -0.202)
			(end -0.101 0)
			(stroke
				(width 0.15)
				(type solid)
			)
			(layer "F.Fab")
		)
		(fp_line
			(start -0.101 0)
			(end 0.201 0.2)
			(stroke
				(width 0.15)
				(type solid)
			)
			(layer "F.Fab")
		)
		(fp_line
			(start -0.199 0.2)
			(end -0.199 0.1)
			(stroke
				(width 0.15)
				(type solid)
			)
			(layer "F.Fab")
		)
		(fp_line
			(start -0.199 0)
			(end -0.597 0)
			(stroke
				(width 0.15)
				(type solid)
			)
			(layer "F.Fab")
		)
		(fp_line
			(start -0.199 -0.202)
			(end -0.199 0.1)
			(stroke
				(width 0.15)
				(type solid)
			)
			(layer "F.Fab")
		)
		(fp_rect
			(start 0.848 0.4)
			(end -0.85 -0.402)
			(stroke
				(width 0.15)
				(type solid)
			)
			(fill no)
			(layer "F.Fab")
		)
		(fp_text user "License: Apache-2.0"
			(at -1.4224 3.599 180)
			(layer "F.Fab")
			(effects
				(font
					(size 0.7 0.7)
					(thickness 0.15)
				)
				(justify left bottom)
			)
		)
		(fp_text user "${REFERENCE}"
			(at -1.4224 5.999 180)
			(layer "F.Fab")
			(effects
				(font
					(size 0.7 0.7)
					(thickness 0.15)
				)
				(justify left bottom)
			)
		)
		(fp_text user "Author: Antmicro"
			(at -1.4224 4.799 180)
			(layer "F.Fab")
			(effects
				(font
					(size 0.7 0.7)
					(thickness 0.15)
				)
				(justify left bottom)
			)
		)
		(pad "1" smd roundrect
			(at -0.7 0)
			(size 0.8 1)
			(layers "F.Cu" "F.Mask" "F.Paste")
			(roundrect_rratio 0.2)
			(net 3 "GND")
			(pinfunction "C")
			(pintype "passive")
		)
		(pad "2" smd roundrect
			(at 0.7 0)
			(size 0.8 1)
			(layers "F.Cu" "F.Mask" "F.Paste")
			(roundrect_rratio 0.2)
			(net 479 "Net-(D601-A)")
			(pinfunction "A")
			(pintype "passive")
		)
	)
	(footprint "antmicro-footprints:TP_SMD_0.75mm"
		(layer "F.Cu")
		(at 97.592962 121.4665)
		(property "Reference" "TP911"
			(at 25.935 26.15 0)
			(layer "F.SilkS")
			(effects
				(font
					(size 0.7 0.7)
					(thickness 0.15)
				)
				(justify left bottom)
			)
		)
		(property "Value" "TP_0.75mm_SMD"
			(at 0 1.2 0)
			(layer "F.Fab")
			(effects
				(font
					(size 0.7 0.7)
					(thickness 0.15)
				)
				(justify left bottom)
			)
		)
		(property "MPN" ""
			(at 0 0 0)
			(unlocked yes)
			(layer "F.Fab")
			(hide yes)
			(effects
				(font
					(size 1 1)
					(thickness 0.15)
				)
			)
		)
		(property "Manufacturer" ""
			(at 0 0 0)
			(unlocked yes)
			(layer "F.Fab")
			(hide yes)
			(effects
				(font
					(size 1 1)
					(thickness 0.15)
				)
			)
		)
		(property "Author" "Antmicro"
			(at 0 0 0)
			(unlocked yes)
			(layer "F.Fab")
			(hide yes)
			(effects
				(font
					(size 1 1)
					(thickness 0.15)
				)
			)
		)
		(property "License" "Apache-2.0"
			(at 0 0 0)
			(unlocked yes)
			(layer "F.Fab")
			(hide yes)
			(effects
				(font
					(size 1 1)
					(thickness 0.15)
				)
			)
		)
		(sheetname "/USB/")
		(sheetfile "usb.kicad_sch")
		(attr exclude_from_pos_files exclude_from_bom)
		(fp_circle
			(center 0 0)
			(end 0.475 0)
			(stroke
				(width 0.05)
				(type default)
			)
			(fill no)
			(layer "F.CrtYd")
		)
		(fp_text user "${REFERENCE}"
			(at -0.4 2.7 0)
			(layer "F.Fab")
			(effects
				(font
					(size 0.7 0.7)
					(thickness 0.15)
				)
				(justify left bottom)
			)
		)
		(fp_text user "License: Apache-2.0"
			(at -0.4 5.101 0)
			(layer "F.Fab")
			(effects
				(font
					(size 0.7 0.7)
					(thickness 0.15)
				)
				(justify left bottom)
			)
		)
		(fp_text user "Author: Antmicro"
			(at -0.4 3.901 0)
			(layer "F.Fab")
			(effects
				(font
					(size 0.7 0.7)
					(thickness 0.15)
				)
				(justify left bottom)
			)
		)
		(pad "1" smd circle
			(at 0 0)
			(size 0.75 0.75)
			(layers "F.Cu" "F.Mask")
			(net 436 "Net-(U906-OUT1)")
			(pinfunction "1")
			(pintype "passive")
		)
	)
	(footprint "antmicro-footprints:TP_SMD_0.75mm"
		(layer "F.Cu")
		(at 47.58 135.3)
		(property "Reference" "TP402"
			(at -2.96 1.57 0)
			(layer "F.SilkS")
			(effects
				(font
					(size 0.7 0.7)
					(thickness 0.15)
				)
				(justify left bottom)
			)
		)
		(property "Value" "TP_0.75mm_SMD"
			(at 0 1.2 0)
			(layer "F.Fab")
			(effects
				(font
					(size 0.7 0.7)
					(thickness 0.15)
				)
				(justify left bottom)
			)
		)
		(property "MPN" ""
			(at 0 0 0)
			(unlocked yes)
			(layer "F.Fab")
			(hide yes)
			(effects
				(font
					(size 1 1)
					(thickness 0.15)
				)
			)
		)
		(property "Manufacturer" ""
			(at 0 0 0)
			(unlocked yes)
			(layer "F.Fab")
			(hide yes)
			(effects
				(font
					(size 1 1)
					(thickness 0.15)
				)
			)
		)
		(property "Author" "Antmicro"
			(at 0 0 0)
			(unlocked yes)
			(layer "F.Fab")
			(hide yes)
			(effects
				(font
					(size 1 1)
					(thickness 0.15)
				)
			)
		)
		(property "License" "Apache-2.0"
			(at 0 0 0)
			(unlocked yes)
			(layer "F.Fab")
			(hide yes)
			(effects
				(font
					(size 1 1)
					(thickness 0.15)
				)
			)
		)
		(sheetname "/Ethernet/")
		(sheetfile "ethernet.kicad_sch")
		(attr exclude_from_pos_files exclude_from_bom)
		(fp_circle
			(center 0 0)
			(end 0.475 0)
			(stroke
				(width 0.05)
				(type default)
			)
			(fill no)
			(layer "F.CrtYd")
		)
		(fp_text user "${REFERENCE}"
			(at -0.4 2.7 0)
			(layer "F.Fab")
			(effects
				(font
					(size 0.7 0.7)
					(thickness 0.15)
				)
				(justify left bottom)
			)
		)
		(fp_text user "Author: Antmicro"
			(at -0.4 3.901 0)
			(layer "F.Fab")
			(effects
				(font
					(size 0.7 0.7)
					(thickness 0.15)
				)
				(justify left bottom)
			)
		)
		(fp_text user "License: Apache-2.0"
			(at -0.4 5.101 0)
			(layer "F.Fab")
			(effects
				(font
					(size 0.7 0.7)
					(thickness 0.15)
				)
				(justify left bottom)
			)
		)
		(pad "1" smd circle
			(at 0 0)
			(size 0.75 0.75)
			(layers "F.Cu" "F.Mask")
			(net 1 "GNDD")
			(pinfunction "1")
			(pintype "passive")
		)
	)
	(footprint "antmicro-footprints:R_0402_1005Metric"
		(layer "F.Cu")
		(at 75.067962 166.7165)
		(descr "Resistor SMD 0402")
		(tags "resistor SMD 0402")
		(property "Reference" "R803"
			(at -1.45 -1.31 0)
			(layer "F.SilkS")
			(effects
				(font
					(size 0.7 0.7)
					(thickness 0.15)
				)
				(justify left bottom)
			)
		)
		(property "Value" "R_10k_0402"
			(at -1.011843 1.772047 0)
			(layer "F.Fab")
			(effects
				(font
					(size 0.7 0.7)
					(thickness 0.15)
				)
				(justify left bottom)
			)
		)
		(property "Datasheet" "https://www.bourns.com/docs/product-datasheets/cr.pdf"
			(at 0 0 0)
			(layer "F.Fab")
			(hide yes)
			(effects
				(font
					(size 1.27 1.27)
					(thickness 0.15)
				)
			)
		)
		(property "MPN" "CR0402-FX-1002GLF"
			(at 0 0 0)
			(unlocked yes)
			(layer "F.Fab")
			(hide yes)
			(effects
				(font
					(size 1 1)
					(thickness 0.15)
				)
			)
		)
		(property "Manufacturer" "Bourns"
			(at 0 0 0)
			(unlocked yes)
			(layer "F.Fab")
			(hide yes)
			(effects
				(font
					(size 1 1)
					(thickness 0.15)
				)
			)
		)
		(property "License" "Apache-2.0"
			(at 0 0 0)
			(unlocked yes)
			(layer "F.Fab")
			(hide yes)
			(effects
				(font
					(size 1 1)
					(thickness 0.15)
				)
			)
		)
		(property "Author" "Antmicro"
			(at 0 0 0)
			(unlocked yes)
			(layer "F.Fab")
			(hide yes)
			(effects
				(font
					(size 1 1)
					(thickness 0.15)
				)
			)
		)
		(property "Val" "10k"
			(at 0 0 0)
			(unlocked yes)
			(layer "F.Fab")
			(hide yes)
			(effects
				(font
					(size 1 1)
					(thickness 0.15)
				)
			)
		)
		(property "Tolerance" "1%"
			(at 0 0 0)
			(unlocked yes)
			(layer "F.Fab")
			(hide yes)
			(effects
				(font
					(size 1 1)
					(thickness 0.15)
				)
			)
		)
		(sheetname "/Peripherals/")
		(sheetfile "peripherals.kicad_sch")
		(attr smd exclude_from_pos_files exclude_from_bom dnp)
		(fp_rect
			(start -0.925 -0.47)
			(end 0.925 0.47)
			(stroke
				(width 0.05)
				(type default)
			)
			(fill no)
			(layer "F.CrtYd")
		)
		(fp_rect
			(start -0.5 -0.25)
			(end 0.5 0.25)
			(stroke
				(width 0.15)
				(type solid)
			)
			(fill no)
			(layer "F.Fab")
		)
		(fp_text user "License: Apache-2.0"
			(at -0.95 5.169 0)
			(layer "F.Fab")
			(effects
				(font
					(size 0.7 0.7)
					(thickness 0.15)
				)
				(justify left bottom)
			)
		)
		(fp_text user "Author: Antmicro"
			(at -0.95 4.169 0)
			(layer "F.Fab")
			(effects
				(font
					(size 0.7 0.7)
					(thickness 0.15)
				)
				(justify left bottom)
			)
		)
		(fp_text user "${REFERENCE}"
			(at -0.95 3.168 0)
			(layer "F.Fab")
			(effects
				(font
					(size 0.7 0.7)
					(thickness 0.15)
				)
				(justify left bottom)
			)
		)
		(pad "1" smd roundrect
			(at -0.48 0)
			(size 0.59 0.64)
			(layers "F.Cu" "F.Mask" "F.Paste")
			(roundrect_rratio 0.25)
			(net 374 "Net-(U801-I2C_ADR0)")
			(pintype "passive")
		)
		(pad "2" smd roundrect
			(at 0.48 0)
			(size 0.59 0.64)
			(layers "F.Cu" "F.Mask" "F.Paste")
			(roundrect_rratio 0.25)
			(net 9 "+3V3")
			(pintype "passive")
		)
	)
)
